(kicad_pcb
	(version 20221018)
	(generator pcbnew)
	(general
    (thickness 1.562)
  )
	(paper "A4")
	(title_block
    (title "Thunderbolt PCIe Adaper")
    (date "2024-07-09")
    (rev "1.0.3")
    (comment 1 "www.antmicro.com")
    (comment 2 "Antmicro Ltd.")
		(comment 9 "footprints 39-43 of 271")
	)
	(layers
    (0 "F.Cu" signal)
    (1 "In1.Cu" signal)
    (2 "In2.Cu" signal)
    (3 "In3.Cu" signal)
    (4 "In4.Cu" signal)
    (31 "B.Cu" signal)
    (32 "B.Adhes" user "B.Adhesive")
    (33 "F.Adhes" user "F.Adhesive")
    (34 "B.Paste" user)
    (35 "F.Paste" user)
    (36 "B.SilkS" user "B.Silkscreen")
    (37 "F.SilkS" user "F.Silkscreen")
    (38 "B.Mask" user)
    (39 "F.Mask" user)
    (40 "Dwgs.User" user "User.Drawings")
    (41 "Cmts.User" user "User.Comments")
    (42 "Eco1.User" user "User.Eco1")
    (43 "Eco2.User" user "User.Eco2")
    (44 "Edge.Cuts" user)
    (45 "Margin" user)
    (46 "B.CrtYd" user "B.Courtyard")
    (47 "F.CrtYd" user "F.Courtyard")
    (48 "B.Fab" user)
    (49 "F.Fab" user)
  )
	(footprint "antmicro-footprints:USB-C_Receptacle_JAE_DX07S024JJ2" (layer "F.Cu")
    (at 166.25 76.053922 90)
    (property "Author" "Antmicro")
    (property "License" "Apache-2.0")
    (property "MPN" "DX07S024JJ2")
    (property "Manufacturer" "JAE Electronics")
    (property "Sheetfile" "connectors.kicad_sch")
    (property "Sheetname" "Connectors")
    (property "ki_description" "USB-C (USB TYPE-C) USB 3.2 Gen 2 (USB 3.1 Gen 2, Superspeed + (USB 3.1)) Receptacle Connector 24 Position Surface Mount, Right Angle")
    (property "ki_keywords" "USB, CONNECTOR, SMT, HORIZONTAL")
    (attr smd)
    (fp_text reference "J1" (at -6.750078 -0.896 180) (layer "F.SilkS")
        (effects (font (size 0.7 0.7) (thickness 0.15)) (justify left bottom))
    )
    (fp_text value "USB-C_JAE_DX07S024JJ2" (at -5 5.6 90) (layer "F.Fab")
        (effects (font (size 0.7 0.7) (thickness 0.15)) (justify left bottom))
    )
    (fp_text user "Author: Antmicro" (at -5.571 7.6 90) (layer "F.Fab") hide
        (effects (font (size 0.7 0.7) (thickness 0.15)) (justify left bottom))
    )
    (fp_text user "${REFERENCE}" (at -5.571 10 90) (layer "F.Fab") hide
        (effects (font (size 0.7 0.7) (thickness 0.15)) (justify left bottom))
    )
    (fp_text user "License: Apache-2.0" (at -5.571 8.8 90) (layer "F.Fab") hide
        (effects (font (size 0.7 0.7) (thickness 0.15)) (justify left bottom))
    )
    (fp_line (start -4.47 -1.645) (end -4.47 0.313)
      (stroke (width 0.15) (type solid)) (layer "F.SilkS"))
    (fp_line (start 4.469 -1.645) (end 4.469 0.313)
      (stroke (width 0.15) (type solid)) (layer "F.SilkS"))
    (fp_circle (center -2.625 -4.885) (end -2.576 -4.885)
      (stroke (width 0.15) (type solid)) (fill solid) (layer "F.SilkS"))
    (fp_rect (start -5.571 -4.885) (end 5.669 4.584)
      (stroke (width 0.05) (type solid)) (fill none) (layer "F.CrtYd"))
    (fp_line (start -4.96 -4.4) (end -4.81 -4.55)
      (stroke (width 0.15) (type solid)) (layer "F.Fab"))
    (fp_rect (start -4.971 -4.575) (end 4.969 4.084)
      (stroke (width 0.15) (type solid)) (fill none) (layer "F.Fab"))
    (pad "" np_thru_hole circle (at -3.601 -1.115 90) (size 0.63 0.63) (drill 0.63) (layers "*.Cu" "*.Mask"))
    (pad "" np_thru_hole oval (at 3.6 -1.18 90) (size 0.88 0.53) (drill oval 0.88 0.53) (layers "F&B.Cu" "*.Mask"))
    (pad "A1" smd rect (at -2.625 -3.817 90) (size 0.27 0.9) (layers "F.Cu" "F.Paste" "F.Mask")
      (net 1 "GND") (pinfunction "GND") (pintype "power_in"))
    (pad "A2" smd rect (at -2.125 -3.817 90) (size 0.27 0.9) (layers "F.Cu" "F.Paste" "F.Mask")
      (net 12 "TB_TX0_P") (pinfunction "TX_{1}+") (pintype "bidirectional"))
    (pad "A3" smd rect (at -1.625 -3.817 90) (size 0.27 0.9) (layers "F.Cu" "F.Paste" "F.Mask")
      (net 17 "TB_TX0_N") (pinfunction "TX_{1}-") (pintype "bidirectional"))
    (pad "A4" smd rect (at -1.125 -3.817 90) (size 0.27 0.9) (layers "F.Cu" "F.Paste" "F.Mask")
      (net 3 "5V0_USB") (pinfunction "VBUS") (pintype "passive"))
    (pad "A5" smd rect (at -0.625 -3.817 90) (size 0.27 0.9) (layers "F.Cu" "F.Paste" "F.Mask")
      (net 11 "CC1") (pinfunction "CC_{1}") (pintype "bidirectional"))
    (pad "A6" smd rect (at -0.125 -3.817 90) (size 0.27 0.9) (layers "F.Cu" "F.Paste" "F.Mask")
      (net 33 "USB_T_P") (pinfunction "D_{A}+") (pintype "bidirectional"))
    (pad "A7" smd rect (at 0.374 -3.817 90) (size 0.27 0.9) (layers "F.Cu" "F.Paste" "F.Mask")
      (net 34 "USB_T_N") (pinfunction "D_{A}-") (pintype "bidirectional"))
    (pad "A8" smd rect (at 0.874 -3.817 90) (size 0.27 0.9) (layers "F.Cu" "F.Paste" "F.Mask")
      (net 35 "SBU1") (pinfunction "SBU_{1}") (pintype "bidirectional"))
    (pad "A9" smd rect (at 1.374 -3.817 90) (size 0.27 0.9) (layers "F.Cu" "F.Paste" "F.Mask")
      (net 3 "5V0_USB") (pinfunction "VBUS") (pintype "passive"))
    (pad "A10" smd rect (at 1.874 -3.817 90) (size 0.27 0.9) (layers "F.Cu" "F.Paste" "F.Mask")
      (net 36 "TB_RX1_N") (pinfunction "RX_{2}-") (pintype "bidirectional"))
    (pad "A11" smd rect (at 2.374 -3.817 90) (size 0.27 0.9) (layers "F.Cu" "F.Paste" "F.Mask")
      (net 37 "TB_RX1_P") (pinfunction "RX_{2}+") (pintype "bidirectional"))
    (pad "A12" smd rect (at 2.874 -3.817 90) (size 0.27 0.9) (layers "F.Cu" "F.Paste" "F.Mask")
      (net 1 "GND") (pinfunction "GND") (pintype "passive"))
    (pad "B1" smd rect (at 2.624 -2.215 90) (size 0.27 0.8) (layers "F.Cu" "F.Paste" "F.Mask")
      (net 1 "GND") (pinfunction "GND") (pintype "passive"))
    (pad "B2" smd rect (at 2.124 -2.215 90) (size 0.27 0.8) (layers "F.Cu" "F.Paste" "F.Mask")
      (net 14 "TB_TX1_P") (pinfunction "TX_{2}+") (pintype "bidirectional"))
    (pad "B3" smd rect (at 1.624 -2.215 90) (size 0.27 0.8) (layers "F.Cu" "F.Paste" "F.Mask")
      (net 21 "TB_TX1_N") (pinfunction "TX_{2}-") (pintype "bidirectional"))
    (pad "B4" smd rect (at 1.124 -2.215 90) (size 0.27 0.8) (layers "F.Cu" "F.Paste" "F.Mask")
      (net 3 "5V0_USB") (pinfunction "VBUS") (pintype "passive"))
    (pad "B5" smd rect (at 0.624 -2.215 90) (size 0.27 0.8) (layers "F.Cu" "F.Paste" "F.Mask")
      (net 10 "CC2") (pinfunction "CC_{2}") (pintype "bidirectional"))
    (pad "B6" smd rect (at 0.124 -2.215 90) (size 0.27 0.8) (layers "F.Cu" "F.Paste" "F.Mask")
      (net 38 "USB_B_P") (pinfunction "D_{B}+") (pintype "bidirectional"))
    (pad "B7" smd rect (at -0.375 -2.215 90) (size 0.27 0.8) (layers "F.Cu" "F.Paste" "F.Mask")
      (net 39 "USB_B_N") (pinfunction "D_{B}-") (pintype "bidirectional"))
    (pad "B8" smd rect (at -0.875 -2.215 90) (size 0.27 0.8) (layers "F.Cu" "F.Paste" "F.Mask")
      (net 40 "SBU2") (pinfunction "SBU_{2}") (pintype "bidirectional"))
    (pad "B9" smd rect (at -1.375 -2.215 90) (size 0.27 0.8) (layers "F.Cu" "F.Paste" "F.Mask")
      (net 3 "5V0_USB") (pinfunction "VBUS") (pintype "passive"))
    (pad "B10" smd rect (at -1.875 -2.215 90) (size 0.27 0.8) (layers "F.Cu" "F.Paste" "F.Mask")
      (net 41 "TB_RX0_N") (pinfunction "RX_{1}-") (pintype "bidirectional"))
    (pad "B11" smd rect (at -2.375 -2.215 90) (size 0.27 0.8) (layers "F.Cu" "F.Paste" "F.Mask")
      (net 42 "TB_RX0_P") (pinfunction "RX_{1}+") (pintype "bidirectional"))
    (pad "B12" smd rect (at -2.875 -2.215 90) (size 0.27 0.8) (layers "F.Cu" "F.Paste" "F.Mask")
      (net 1 "GND") (pinfunction "GND") (pintype "passive"))
    (pad "SH" thru_hole oval (at -4.321 1.933 90) (size 1.3 2.6) (drill oval 0.75 2.05) (layers "*.Cu" "*.Mask")
      (net 1 "GND") (pinfunction "SH") (pintype "passive"))
    (pad "SH" thru_hole custom (at -4.32 -3.12 90) (size 1.2 1.2) (drill oval 0.6 1.9) (layers "*.Cu" "*.Mask")
      (net 1 "GND") (pinfunction "SH") (pintype "passive") (thermal_bridge_angle 90)
      (options (clearance outline) (anchor circle))
      (primitives
        (gr_line (start 0.6 0.6) (end 0 0.6) (width 1.1))
        (gr_line (start 0 -0.55) (end 0 0.55) (width 1.2))
      ))
    (pad "SH" thru_hole oval (at -3.99 -2.52 180) (size 1 1.55) (drill oval 0.7 1.25) (layers "*.Cu" "*.Mask")
      (net 1 "GND") (pinfunction "SH") (pintype "passive"))
    (pad "SH" thru_hole oval (at 3.99 -2.52) (size 1 1.55) (drill oval 0.7 1.25) (layers "*.Cu" "*.Mask")
      (net 1 "GND") (pinfunction "SH") (pintype "passive"))
    (pad "SH" thru_hole custom (at 4.32 -3.12 90) (size 1.2 1.2) (drill oval 0.6 1.9) (layers "*.Cu" "*.Mask")
      (net 1 "GND") (pinfunction "SH") (pintype "passive") (thermal_bridge_angle 90)
      (options (clearance outline) (anchor circle))
      (primitives
        (gr_line (start -0.6 0.6) (end 0 0.6) (width 1.1))
        (gr_line (start 0 -0.55) (end 0 0.55) (width 1.2))
      ))
    (pad "SH" thru_hole oval (at 4.32 1.933 90) (size 1.3 2.6) (drill oval 0.75 2.05) (layers "*.Cu" "*.Mask")
      (net 1 "GND") (pinfunction "SH") (pintype "passive"))
    (zone (net 0) (net_name "") (layer "F.Cu") (name "TOP_KEEPOUT") (hatch full 0.508)
      (connect_pads (clearance 0))
      (min_thickness 0.01) (filled_areas_thickness no)
      (keepout (tracks not_allowed) (vias not_allowed) (pads not_allowed) (copperpour not_allowed) (footprints allowed))
      (fill (thermal_gap 0.508) (thermal_bridge_width 0.508))
      (polygon
        (pts
          (xy 165.419992 72.154914)
          (xy 165.420073 72.954186)
          (xy 164.734081 72.955194)
          (xy 164.734 79.293922)
          (xy 165.5 79.293922)
          (xy 165.5 79.953922)
          (xy 166.883 79.953922)
          (xy 166.883 79.604922)
          (xy 169.483 79.604922)
          (xy 169.483 79.953922)
          (xy 169.983 79.953922)
          (xy 169.983 72.154922)
          (xy 169.483 72.154922)
          (xy 169.483 72.503922)
          (xy 166.883 72.503922)
          (xy 166.883 72.154922)
        )
      )
    )
  )
	(footprint "antmicro-footprints:C_0805_2012Metric" (layer "F.Cu")
    (at 163.34 65.35 90)
    (descr "Capacitor SMD 0805")
    (tags "capacitor SMD 0805")
    (property "Author" "Antmicro")
    (property "Dielectric" "X5R")
    (property "License" "Apache-2.0")
    (property "MPN" "CL21A226MAYNNNE")
    (property "Manufacturer" "Samsung Electro-Mechanics")
    (property "Sheetfile" "power.kicad_sch")
    (property "Sheetname" "Power")
    (property "Val" "22u")
    (property "Voltage" "25V")
    (property "ki_description" "SMT Multilayer Ceramic Capacitor, 22uF, +/-20%, 25V, X5R, 0805 [2012 Metric]")
    (property "ki_keywords" "0805, SMT, CAPACITOR, PASSIVE")
    (attr smd)
    (fp_text reference "C48" (at -4.119 0.388 90) (layer "F.SilkS")
        (effects (font (size 0.7 0.7) (thickness 0.15)) (justify left bottom))
    )
    (fp_text value "C_22u_25V_0805" (at -2.055717 1.963152 90) (layer "F.Fab")
        (effects (font (size 0.7 0.7) (thickness 0.15)) (justify left bottom))
    )
    (fp_text user "License: Apache-2.0" (at -1.9 4.947 90) (layer "F.Fab") hide
        (effects (font (size 0.7 0.7) (thickness 0.15)) (justify left bottom))
    )
    (fp_text user "Author: Antmicro" (at -1.9 5.947 90) (layer "F.Fab") hide
        (effects (font (size 0.7 0.7) (thickness 0.15)) (justify left bottom))
    )
    (fp_text user "${REFERENCE}" (at -1.9 3.947 90) (layer "F.Fab") hide
        (effects (font (size 0.7 0.7) (thickness 0.15)) (justify left bottom))
    )
    (fp_line (start -0.3 -0.7) (end 0.3 -0.7)
      (stroke (width 0.15) (type solid)) (layer "F.SilkS"))
    (fp_line (start -0.3 0.7) (end 0.3 0.7)
      (stroke (width 0.15) (type solid)) (layer "F.SilkS"))
    (fp_rect (start 1.95 -0.9) (end -1.95 0.9)
      (stroke (width 0.05) (type default)) (fill none) (layer "F.CrtYd"))
    (fp_rect (start -0.95 -0.675) (end 0.95 0.675)
      (stroke (width 0.15) (type solid)) (fill none) (layer "F.Fab"))
    (pad "1" smd roundrect (at -1.1 0 90) (size 1.2 1.3) (layers "F.Cu" "F.Paste" "F.Mask") (roundrect_rratio 0.25)
      (net 1 "GND") (pintype "passive"))
    (pad "2" smd roundrect (at 1.1 0 90) (size 1.2 1.3) (layers "F.Cu" "F.Paste" "F.Mask") (roundrect_rratio 0.25)
      (net 32 "VBUS") (pintype "passive"))
  )
	(footprint "antmicro-footprints:C_0603_1608Metric" (layer "F.Cu")
    (at 113.675 87.875)
    (descr "Capacitor SMD 0603")
    (tags "capacitor 0603")
    (property "Author" "Antmicro")
    (property "Dielectric" "")
    (property "License" "Apache-2.0")
    (property "MPN" "CL10A226MO7JZNC")
    (property "Manufacturer" "Samsung Electro-Mechanics")
    (property "Sheetfile" "power.kicad_sch")
    (property "Sheetname" "Power")
    (property "Val" "22u")
    (property "Voltage" "16V")
    (property "ki_description" "SMD Multilayer Ceramic Capacitor")
    (property "ki_keywords" "0603, SMT, CAPACITOR, PASSIVE, CERAMIC")
    (attr smd)
    (fp_text reference "C50" (at -1.026 -0.753) (layer "F.SilkS")
        (effects (font (size 0.7 0.7) (thickness 0.15)) (justify left bottom))
    )
    (fp_text value "C_22u_16V_0603" (at -1.42757 1.770288) (layer "F.Fab")
        (effects (font (size 0.7 0.7) (thickness 0.15)) (justify left bottom))
    )
    (fp_text user "${REFERENCE}" (at -1.682 3.895) (layer "F.Fab") hide
        (effects (font (size 0.7 0.7) (thickness 0.15)) (justify left bottom))
    )
    (fp_text user "License: Apache-2.0" (at -1.682 5.895) (layer "F.Fab") hide
        (effects (font (size 0.7 0.7) (thickness 0.15)) (justify left bottom))
    )
    (fp_text user "Author: Antmicro" (at -1.682 4.894) (layer "F.Fab") hide
        (effects (font (size 0.7 0.7) (thickness 0.15)) (justify left bottom))
    )
    (fp_line (start -0.15 -0.4) (end 0.15 -0.4)
      (stroke (width 0.15) (type solid)) (layer "F.SilkS"))
    (fp_line (start -0.15 0.4) (end 0.15 0.4)
      (stroke (width 0.15) (type solid)) (layer "F.SilkS"))
    (fp_rect (start -1.25 -0.65) (end 1.25 0.65)
      (stroke (width 0.05) (type solid)) (fill none) (layer "F.CrtYd"))
    (fp_rect (start -0.8 -0.4) (end 0.8 0.4)
      (stroke (width 0.15) (type solid)) (fill none) (layer "F.Fab"))
    (pad "1" smd roundrect (at -0.7 0) (size 0.8 1) (layers "F.Cu" "F.Paste" "F.Mask") (roundrect_rratio 0.2)
      (net 1 "GND") (pintype "passive"))
    (pad "2" smd roundrect (at 0.7 0) (size 0.8 1) (layers "F.Cu" "F.Paste" "F.Mask") (roundrect_rratio 0.2)
      (net 60 "12V0_DCDC") (pintype "passive"))
  )
	(footprint "antmicro-footprints:C_0805_2012Metric" (layer "F.Cu")
    (at 161.41 65.35 90)
    (descr "Capacitor SMD 0805")
    (tags "capacitor SMD 0805")
    (property "Author" "Antmicro")
    (property "Dielectric" "X5R")
    (property "License" "Apache-2.0")
    (property "MPN" "CL21A226MAYNNNE")
    (property "Manufacturer" "Samsung Electro-Mechanics")
    (property "Sheetfile" "power.kicad_sch")
    (property "Sheetname" "Power")
    (property "Val" "22u")
    (property "Voltage" "25V")
    (property "ki_description" "SMT Multilayer Ceramic Capacitor, 22uF, +/-20%, 25V, X5R, 0805 [2012 Metric]")
    (property "ki_keywords" "0805, SMT, CAPACITOR, PASSIVE")
    (attr smd)
    (fp_text reference "C42" (at -4.119 0.388 90) (layer "F.SilkS")
        (effects (font (size 0.7 0.7) (thickness 0.15)) (justify left bottom))
    )
    (fp_text value "C_22u_25V_0805" (at -2.055717 1.963152 90) (layer "F.Fab")
        (effects (font (size 0.7 0.7) (thickness 0.15)) (justify left bottom))
    )
    (fp_text user "${REFERENCE}" (at -1.9 3.947 90) (layer "F.Fab") hide
        (effects (font (size 0.7 0.7) (thickness 0.15)) (justify left bottom))
    )
    (fp_text user "License: Apache-2.0" (at -1.9 4.947 90) (layer "F.Fab") hide
        (effects (font (size 0.7 0.7) (thickness 0.15)) (justify left bottom))
    )
    (fp_text user "Author: Antmicro" (at -1.9 5.947 90) (layer "F.Fab") hide
        (effects (font (size 0.7 0.7) (thickness 0.15)) (justify left bottom))
    )
    (fp_line (start -0.3 -0.7) (end 0.3 -0.7)
      (stroke (width 0.15) (type solid)) (layer "F.SilkS"))
    (fp_line (start -0.3 0.7) (end 0.3 0.7)
      (stroke (width 0.15) (type solid)) (layer "F.SilkS"))
    (fp_rect (start 1.95 -0.9) (end -1.95 0.9)
      (stroke (width 0.05) (type default)) (fill none) (layer "F.CrtYd"))
    (fp_rect (start -0.95 -0.675) (end 0.95 0.675)
      (stroke (width 0.15) (type solid)) (fill none) (layer "F.Fab"))
    (pad "1" smd roundrect (at -1.1 0 90) (size 1.2 1.3) (layers "F.Cu" "F.Paste" "F.Mask") (roundrect_rratio 0.25)
      (net 1 "GND") (pintype "passive"))
    (pad "2" smd roundrect (at 1.1 0 90) (size 1.2 1.3) (layers "F.Cu" "F.Paste" "F.Mask") (roundrect_rratio 0.25)
      (net 32 "VBUS") (pintype "passive"))
  )
	(footprint "antmicro-footprints:Vishay_PowerPAK_1212-8_Single" (layer "F.Cu")
    (at 115.2475 90.8)
    (descr "PowerPAK 1212-8 Single")
    (tags "Vishay PowerPAK 1212-8 Single")
    (property "Author" "Antmicro")
    (property "License" "Apache-2.0")
    (property "MPN" "SI7613DN-T1-GE3")
    (property "Manufacturer" "Vishay")
    (property "Sheetfile" "power.kicad_sch")
    (property "Sheetname" "Power")
    (property "ki_description" "Power MOSFET, P Channel, 20 V, 35 A, 0.0072 ohm, PowerPAK 1212, Surface Mount")
    (property "ki_keywords" "SMT, TRANSISTOR, SEMICONDUCTOR, MOSFET, PMOS")
    (attr smd)
    (fp_text reference "Q6" (at 2.4815 3.18) (layer "F.SilkS")
        (effects (font (size 0.7 0.7) (thickness 0.15)) (justify left bottom))
    )
    (fp_text value "SI7613DN-T1-GE3" (at 0 2.7) (layer "F.Fab")
        (effects (font (size 0.7 0.7) (thickness 0.15)) (justify left bottom))
    )
    (fp_text user "Author: Antmicro" (at -8 5.9) (layer "F.Fab") hide
        (effects (font (size 0.7 0.7) (thickness 0.15)) (justify left bottom))
    )
    (fp_text user "${REFERENCE}" (at -8 4.7) (layer "F.Fab") hide
        (effects (font (size 0.7 0.7) (thickness 0.15)) (justify left bottom))
    )
    (fp_text user "License: Apache-2.0" (at -8 7.1) (layer "F.Fab") hide
        (effects (font (size 0.7 0.7) (thickness 0.15)) (justify left bottom))
    )
    (fp_line (start -1.651 -1.651) (end -1.651 -1.317)
      (stroke (width 0.15) (type solid)) (layer "F.SilkS"))
    (fp_line (start -1.651 -1.651) (end 1.648 -1.651)
      (stroke (width 0.15) (type solid)) (layer "F.SilkS"))
    (fp_line (start -1.635 1.3) (end -1.635 1.634)
      (stroke (width 0.15) (type solid)) (layer "F.SilkS"))
    (fp_line (start -1.635 1.634) (end 1.634 1.634)
      (stroke (width 0.15) (type solid)) (layer "F.SilkS"))
    (fp_line (start 1.634 1.3) (end 1.634 1.634)
      (stroke (width 0.15) (type solid)) (layer "F.SilkS"))
    (fp_line (start 1.648 -1.651) (end 1.648 -1.317)
      (stroke (width 0.15) (type solid)) (layer "F.SilkS"))
    (fp_circle (center -1.9 -1.4) (end -1.85 -1.4)
      (stroke (width 0.15) (type solid)) (fill solid) (layer "F.SilkS"))
    (fp_rect (start -2 -1.8) (end 2 1.798)
      (stroke (width 0.05) (type solid)) (fill none) (layer "F.CrtYd"))
    (fp_line (start -1.6425 -1.4175) (end -1.4175 -1.6425)
      (stroke (width 0.15) (type solid)) (layer "F.Fab"))
    (fp_rect (start -1.651 -1.651) (end 1.648 1.648)
      (stroke (width 0.15) (type solid)) (fill none) (layer "F.Fab"))
    (pad "1" smd rect (at -1.436 -0.99) (size 0.99 0.405) (layers "F.Cu" "F.Paste" "F.Mask")
      (net 146 "Net-(Q4-S)") (pinfunction "S") (pintype "passive"))
    (pad "2" smd rect (at -1.436 -0.332) (size 0.99 0.405) (layers "F.Cu" "F.Paste" "F.Mask")
      (net 146 "Net-(Q4-S)") (pinfunction "S") (pintype "passive"))
    (pad "3" smd rect (at -1.436 0.33) (size 0.99 0.405) (layers "F.Cu" "F.Paste" "F.Mask")
      (net 146 "Net-(Q4-S)") (pinfunction "S") (pintype "passive"))
    (pad "4" smd rect (at -1.436 0.988) (size 0.99 0.405) (layers "F.Cu" "F.Paste" "F.Mask")
      (net 145 "Net-(Q4-BIAS)") (pinfunction "G") (pintype "passive"))
    (pad "5" smd custom (at 0.557 0) (size 1.725 2.235) (layers "F.Cu" "F.Paste" "F.Mask")
      (net 60 "12V0_DCDC") (pinfunction "D") (pintype "passive") (zone_connect 2)
      (options (clearance outline) (anchor rect))
      (primitives
        (gr_poly
          (pts
            (xy 0.8625 0.1275)
            (xy 0.8625 -0.1275)
            (xy 1.3725 -0.1275)
            (xy 1.3725 -0.5325)
            (xy 0.8625 -0.5325)
            (xy 0.8625 -0.7875)
            (xy 1.3725 -0.7875)
            (xy 1.3725 -1.195)
            (xy 0.6125 -1.195)
            (xy 0.6125 1.195)
            (xy 1.3725 1.195)
            (xy 1.3725 0.7875)
            (xy 0.8625 0.7875)
            (xy 0.8625 0.5325)
            (xy 1.3725 0.5325)
            (xy 1.3725 0.1275)
          )
          (width 0) (fill yes))
      ))
  )
)
